# T6G (Grand Teton) — schematic netlist excerpt (pin names and nets, part order shuffled) for the footprints in the layout excerpt that follows; sources: Cadence DE-HDL packaged netlist, KiCad conversion of 04192023_DAF0TMB3IC0_F0TG_MB_C_brd_V02_OCP.brd

R315  Q_RES  49.9 1% CHIP  pkg 0402LF  page 193 : A = PVDDCR_CPU0_P0_RESET_N ; B = PVDDCR_CPU0_P0_RESET_N_R
C6610  Q_CAP_DIFFBUS  DIFF BUS_0.22UF 6.3V 20% X6S  pkg C0201  page 308 : \1\ = P5E_CPU0_P3_TX_BUF_C_DN<6> ; \2\ = P5E_CPU0_P3_TX_BUF_DN<6>
C5232  Q_CAP  0.1UF 25V 10% EMPTY  pkg C0402  page 234 : A = PD_U5201_RSTN ; B = GND

(kicad_pcb
	(version 20260206)
	(generator "pcbnew")
	(generator_version "10.0")
	(general
		(thickness 1.6)
		(legacy_teardrops no)
	)
	(paper "A4")
	(title_block
		(title "04192023_DAF0TMB3IC0_F0TG_MB_C_brd_V02_OCP.brd")
		(comment 1 "Grand Teton / footprints 5965-5967 of 8354")
	)
	(layers
		(0 "F.Cu" signal "TOP")
		(4 "In1.Cu" signal "GND")
		(6 "In2.Cu" signal "IN1")
		(8 "In3.Cu" signal "GND1")
		(10 "In4.Cu" signal "IN2")
		(12 "In5.Cu" signal "GND2")
		(14 "In6.Cu" signal "IN3")
		(16 "In7.Cu" signal "GND3")
		(18 "In8.Cu" signal "VCC")
		(20 "In9.Cu" signal "VCC1")
		(22 "In10.Cu" signal "GND4")
		(24 "In11.Cu" signal "IN4")
		(26 "In12.Cu" signal "GND5")
		(28 "In13.Cu" signal "IN5")
		(30 "In14.Cu" signal "GND6")
		(32 "In15.Cu" signal "IN6")
		(34 "In16.Cu" signal "GND7")
		(2 "B.Cu" signal "BOTTOM")
		(9 "F.Adhes" user "F.Adhesive")
		(11 "B.Adhes" user "B.Adhesive")
		(13 "F.Paste" user "Package Geometry/Pastemask Top")
		(15 "B.Paste" user "Package Geometry/Pastemask Bottom")
		(5 "F.SilkS" user "Ref Des/Silkscreen Top")
		(7 "B.SilkS" user "Ref Des/Silkscreen Bottom")
		(1 "F.Mask" user "Board Geometry/Soldermask Top")
		(3 "B.Mask" user "Board Geometry/Soldermask Bottom")
		(17 "Dwgs.User" user "User.Drawings")
		(19 "Cmts.User" user "User.Comments")
		(21 "Eco1.User" user "User.Eco1")
		(23 "Eco2.User" user "User.Eco2")
		(25 "Edge.Cuts" user "Board Geometry/Outline")
		(27 "Margin" user)
		(31 "F.CrtYd" user "Package Geometry/Place Bound Top")
		(29 "B.CrtYd" user "Package Geometry/Place Bound Bottom")
		(35 "F.Fab" user "Ref Des/Assembly Top")
		(33 "B.Fab" user "Ref Des/Assembly Bottom")
	)
	(footprint ""
		(layer "B.Cu")
		(at 372.937278 -141.472158 180)
		(property "Reference" "R315"
			(at 0 0 0)
			(layer "B.SilkS")
			(hide yes)
			(effects
				(font
					(size 1.27 1.27)
				)
				(justify mirror)
			)
		)
		(property "Value" ""
			(at 0 0 0)
			(layer "B.Fab")
			(effects
				(font
					(size 1.27 1.27)
				)
				(justify mirror)
			)
		)
		(duplicate_pad_numbers_are_jumpers no)
		(fp_line
			(start 0.7874 0.4064)
			(end 0.7874 -0.4064)
			(stroke
				(width 0.1524)
				(type default)
			)
			(layer "B.SilkS")
		)
		(fp_line
			(start 0.7874 -0.4064)
			(end -0.7874 -0.4064)
			(stroke
				(width 0.1524)
				(type default)
			)
			(layer "B.SilkS")
		)
		(fp_line
			(start -0.7874 0.4064)
			(end 0.7874 0.4064)
			(stroke
				(width 0.1524)
				(type default)
			)
			(layer "B.SilkS")
		)
		(fp_line
			(start -0.7874 -0.4064)
			(end -0.7874 0.4064)
			(stroke
				(width 0.1524)
				(type default)
			)
			(layer "B.SilkS")
		)
		(fp_line
			(start 0.67945 0.3048)
			(end 0.67945 -0.305054)
			(stroke
				(width 0.1)
				(type default)
			)
			(layer "B.Fab")
		)
		(fp_line
			(start 0.67945 -0.305054)
			(end 0.12065 -0.305054)
			(stroke
				(width 0.1)
				(type default)
			)
			(layer "B.Fab")
		)
		(fp_line
			(start 0.12065 0.3048)
			(end 0.67945 0.3048)
			(stroke
				(width 0.1)
				(type default)
			)
			(layer "B.Fab")
		)
		(fp_line
			(start 0.12065 0.2794)
			(end 0.12065 0.3048)
			(stroke
				(width 0.1)
				(type default)
			)
			(layer "B.Fab")
		)
		(fp_line
			(start 0.12065 -0.2794)
			(end -0.12065 -0.2794)
			(stroke
				(width 0.1)
				(type default)
			)
			(layer "B.Fab")
		)
		(fp_line
			(start 0.12065 -0.305054)
			(end 0.12065 -0.2794)
			(stroke
				(width 0.1)
				(type default)
			)
			(layer "B.Fab")
		)
		(fp_line
			(start -0.120396 0.3048)
			(end -0.120396 0.2794)
			(stroke
				(width 0.1)
				(type default)
			)
			(layer "B.Fab")
		)
		(fp_line
			(start -0.120396 0.2794)
			(end 0.12065 0.2794)
			(stroke
				(width 0.1)
				(type default)
			)
			(layer "B.Fab")
		)
		(fp_line
			(start -0.12065 -0.2794)
			(end -0.12065 -0.3048)
			(stroke
				(width 0.1)
				(type default)
			)
			(layer "B.Fab")
		)
		(fp_line
			(start -0.12065 -0.3048)
			(end -0.67945 -0.3048)
			(stroke
				(width 0.1)
				(type default)
			)
			(layer "B.Fab")
		)
		(fp_line
			(start -0.67945 0.3048)
			(end -0.120396 0.3048)
			(stroke
				(width 0.1)
				(type default)
			)
			(layer "B.Fab")
		)
		(fp_line
			(start -0.67945 -0.3048)
			(end -0.67945 0.3048)
			(stroke
				(width 0.1)
				(type default)
			)
			(layer "B.Fab")
		)
		(pad "1" smd circle
			(at 0.40005 0)
			(size 0 0)
			(layers "B.Cu" "B.Mask" "B.Paste")
			(net "PVDDCR_CPU0_P0_RESET_N")
		)
		(pad "2" smd circle
			(at -0.40005 0)
			(size 0 0)
			(layers "B.Cu" "B.Mask" "B.Paste")
			(net "PVDDCR_CPU0_P0_RESET_N_R")
		)
	)
	(footprint ""
		(layer "B.Cu")
		(at 8.19277 -112.04702)
		(property "Reference" "C5232"
			(at 0 0 0)
			(layer "B.SilkS")
			(hide yes)
			(effects
				(font
					(size 1.27 1.27)
				)
				(justify mirror)
			)
		)
		(property "Value" ""
			(at 0 0 0)
			(layer "B.Fab")
			(effects
				(font
					(size 1.27 1.27)
				)
				(justify mirror)
			)
		)
		(duplicate_pad_numbers_are_jumpers no)
		(fp_line
			(start -0.7874 -0.4064)
			(end -0.7874 0.4064)
			(stroke
				(width 0.1524)
				(type default)
			)
			(layer "B.SilkS")
		)
		(fp_line
			(start -0.7874 0.4064)
			(end 0.7874 0.4064)
			(stroke
				(width 0.1524)
				(type default)
			)
			(layer "B.SilkS")
		)
		(fp_line
			(start 0.7874 -0.4064)
			(end -0.7874 -0.4064)
			(stroke
				(width 0.1524)
				(type default)
			)
			(layer "B.SilkS")
		)
		(fp_line
			(start 0.7874 0.4064)
			(end 0.7874 -0.4064)
			(stroke
				(width 0.1524)
				(type default)
			)
			(layer "B.SilkS")
		)
		(fp_line
			(start -0.67945 -0.3048)
			(end -0.67945 0.3048)
			(stroke
				(width 0.1)
				(type default)
			)
			(layer "B.Fab")
		)
		(fp_line
			(start -0.67945 0.3048)
			(end -0.120396 0.3048)
			(stroke
				(width 0.1)
				(type default)
			)
			(layer "B.Fab")
		)
		(fp_line
			(start -0.12065 -0.3048)
			(end -0.67945 -0.3048)
			(stroke
				(width 0.1)
				(type default)
			)
			(layer "B.Fab")
		)
		(fp_line
			(start -0.12065 -0.2794)
			(end -0.12065 -0.3048)
			(stroke
				(width 0.1)
				(type default)
			)
			(layer "B.Fab")
		)
		(fp_line
			(start -0.120396 0.2794)
			(end 0.12065 0.2794)
			(stroke
				(width 0.1)
				(type default)
			)
			(layer "B.Fab")
		)
		(fp_line
			(start -0.120396 0.3048)
			(end -0.120396 0.2794)
			(stroke
				(width 0.1)
				(type default)
			)
			(layer "B.Fab")
		)
		(fp_line
			(start 0.12065 -0.305054)
			(end 0.12065 -0.2794)
			(stroke
				(width 0.1)
				(type default)
			)
			(layer "B.Fab")
		)
		(fp_line
			(start 0.12065 -0.2794)
			(end -0.12065 -0.2794)
			(stroke
				(width 0.1)
				(type default)
			)
			(layer "B.Fab")
		)
		(fp_line
			(start 0.12065 0.2794)
			(end 0.12065 0.3048)
			(stroke
				(width 0.1)
				(type default)
			)
			(layer "B.Fab")
		)
		(fp_line
			(start 0.12065 0.3048)
			(end 0.67945 0.3048)
			(stroke
				(width 0.1)
				(type default)
			)
			(layer "B.Fab")
		)
		(fp_line
			(start 0.67945 -0.305054)
			(end 0.12065 -0.305054)
			(stroke
				(width 0.1)
				(type default)
			)
			(layer "B.Fab")
		)
		(fp_line
			(start 0.67945 0.3048)
			(end 0.67945 -0.305054)
			(stroke
				(width 0.1)
				(type default)
			)
			(layer "B.Fab")
		)
		(pad "1" smd circle
			(at 0.40005 0 180)
			(size 0 0)
			(layers "B.Cu" "B.Mask" "B.Paste")
			(net "PD_U5201_RSTN")
		)
		(pad "2" smd circle
			(at -0.40005 0 180)
			(size 0 0)
			(layers "B.Cu" "B.Mask" "B.Paste")
			(net "GND")
		)
	)
	(footprint ""
		(layer "B.Cu")
		(at 390.779762 -416.899344 90)
		(property "Reference" "C6610"
			(at 0 0 90)
			(layer "B.SilkS")
			(hide yes)
			(effects
				(font
					(size 1.27 1.27)
				)
				(justify mirror)
			)
		)
		(property "Value" ""
			(at 0 0 90)
			(layer "B.Fab")
			(effects
				(font
					(size 1.27 1.27)
				)
				(justify mirror)
			)
		)
		(duplicate_pad_numbers_are_jumpers no)
		(fp_line
			(start 0.299974 -0.150114)
			(end -0.299974 -0.150114)
			(stroke
				(width 0.1)
				(type default)
			)
			(layer "B.Fab")
		)
		(fp_line
			(start -0.299974 -0.150114)
			(end -0.299974 0.150114)
			(stroke
				(width 0.1)
				(type default)
			)
			(layer "B.Fab")
		)
		(fp_line
			(start 0.299974 0.150114)
			(end 0.299974 -0.150114)
			(stroke
				(width 0.1)
				(type default)
			)
			(layer "B.Fab")
		)
		(fp_line
			(start -0.299974 0.150114)
			(end 0.299974 0.150114)
			(stroke
				(width 0.1)
				(type default)
			)
			(layer "B.Fab")
		)
		(pad "1" smd rect
			(at 0.2667 0 270)
			(size 0.3048 0.381)
			(layers "B.Cu" "B.Mask" "B.Paste")
			(net "P5E_CPU0_P3_TX_BUF_C_DN<6>")
		)
		(pad "2" smd rect
			(at -0.2667 0 270)
			(size 0.3048 0.381)
			(layers "B.Cu" "B.Mask" "B.Paste")
			(net "P5E_CPU0_P3_TX_BUF_DN<6>")
		)
	)
)
